(kicad_pcb
	(version 20260206)
	(generator "pcbnew")
	(generator_version "10.0")
	(general
		(thickness 1.6)
		(legacy_teardrops no)
	)
	(paper "A4")
	(title_block
		(title "Wiwynn_Tioga_Pass_MB.brd")
		(comment 1 "Tioga Pass / footprints 4059-4066 of 4770")
	)
	(layers
		(0 "F.Cu" signal "TOP")
		(4 "In1.Cu" signal "L2GND")
		(6 "In2.Cu" signal "L3")
		(8 "In3.Cu" signal "L4GND")
		(10 "In4.Cu" signal "L5")
		(12 "In5.Cu" signal "L6GND")
		(14 "In6.Cu" signal "L7VCC")
		(16 "In7.Cu" signal "L8VCC")
		(18 "In8.Cu" signal "L9GND")
		(20 "In9.Cu" signal "L10")
		(22 "In10.Cu" signal "L11GND")
		(24 "In11.Cu" signal "L12")
		(26 "In12.Cu" signal "L13GND")
		(2 "B.Cu" signal "BOTTOM")
		(9 "F.Adhes" user "F.Adhesive")
		(11 "B.Adhes" user "B.Adhesive")
		(13 "F.Paste" user "Package Geometry/Pastemask Top")
		(15 "B.Paste" user "Package Geometry/Pastemask Bottom")
		(5 "F.SilkS" user "Ref Des/Silkscreen Top")
		(7 "B.SilkS" user "Ref Des/Silkscreen Bottom")
		(1 "F.Mask" user "Board Geometry/Soldermask Top")
		(3 "B.Mask" user "Board Geometry/Soldermask Bottom")
		(17 "Dwgs.User" user "User.Drawings")
		(19 "Cmts.User" user "User.Comments")
		(21 "Eco1.User" user "User.Eco1")
		(23 "Eco2.User" user "User.Eco2")
		(25 "Edge.Cuts" user "Board Geometry/Outline")
		(27 "Margin" user)
		(31 "F.CrtYd" user "Package Geometry/Place Bound Top")
		(29 "B.CrtYd" user "Package Geometry/Place Bound Bottom")
		(35 "F.Fab" user "Ref Des/Assembly Top")
		(33 "B.Fab" user "Ref Des/Assembly Bottom")
	)
	(footprint ""
		(layer "B.Cu")
		(at 162.175952 -62.487302 180)
		(property "Reference" "R7R1"
			(at 0 0 0)
			(layer "B.SilkS")
			(hide yes)
			(effects
				(font
					(size 1.27 1.27)
				)
				(justify mirror)
			)
		)
		(property "Value" ""
			(at 0 0 0)
			(layer "B.Fab")
			(effects
				(font
					(size 1.27 1.27)
				)
				(justify mirror)
			)
		)
		(duplicate_pad_numbers_are_jumpers no)
		(fp_poly
			(pts
				(xy 0.2794 -0.1016) (xy -0.2794 -0.1016) (xy -0.2794 0.9906) (xy 0.2794 0.9906)
			)
			(stroke
				(width 0)
				(type default)
			)
			(fill no)
			(layer "B.CrtYd")
		)
		(fp_line
			(start 0.2794 0.9906)
			(end -0.2794 0.9906)
			(stroke
				(width 0.1)
				(type default)
			)
			(layer "B.Fab")
		)
		(fp_line
			(start 0.2794 -0.1016)
			(end 0.2794 0.9906)
			(stroke
				(width 0.1)
				(type default)
			)
			(layer "B.Fab")
		)
		(fp_line
			(start -0.2794 0.9906)
			(end -0.2794 -0.1016)
			(stroke
				(width 0.1)
				(type default)
			)
			(layer "B.Fab")
		)
		(fp_line
			(start -0.2794 -0.1016)
			(end 0.2794 -0.1016)
			(stroke
				(width 0.1)
				(type default)
			)
			(layer "B.Fab")
		)
		(pad "1" smd rect
			(at 0 0)
			(size 0.508 0.508)
			(layers "B.Cu" "B.Mask" "B.Paste")
			(net "PVCCIO_CPU1")
		)
		(pad "2" smd rect
			(at 0 0.889)
			(size 0.508 0.508)
			(layers "B.Cu" "B.Mask" "B.Paste")
			(net "GND")
		)
		(zone
			(layer "B.Cu")
			(hatch none 0.5)
			(connect_pads
				(clearance 0)
			)
			(min_thickness 0.25)
			(keepout
				(tracks not_allowed)
				(vias allowed)
				(pads allowed)
				(copperpour not_allowed)
				(footprints allowed)
			)
			(placement
				(enabled no)
				(sheetname "")
			)
			(fill
				(thermal_gap 0.5)
				(thermal_bridge_width 0.5)
				(island_removal_mode 0)
			)
			(polygon
				(pts
					(xy 161.921952 -63.122302) (xy 162.429952 -63.122302) (xy 162.429952 -62.741302) (xy 161.921952 -62.741302)
				)
			)
		)
		(zone
			(layer "B.Cu")
			(hatch none 0.5)
			(connect_pads
				(clearance 0)
			)
			(min_thickness 0.25)
			(keepout
				(tracks allowed)
				(vias not_allowed)
				(pads allowed)
				(copperpour not_allowed)
				(footprints allowed)
			)
			(placement
				(enabled no)
				(sheetname "")
			)
			(fill
				(thermal_gap 0.5)
				(thermal_bridge_width 0.5)
				(island_removal_mode 0)
			)
			(polygon
				(pts
					(xy 161.921952 -62.741302) (xy 162.429952 -62.741302) (xy 162.429952 -63.122302) (xy 161.921952 -63.122302)
				)
			)
		)
	)
	(footprint ""
		(layer "B.Cu")
		(at 32.258 -62.6364 90)
		(property "Reference" "R9R11"
			(at 0 0 90)
			(layer "B.SilkS")
			(hide yes)
			(effects
				(font
					(size 1.27 1.27)
				)
				(justify mirror)
			)
		)
		(property "Value" ""
			(at 0 0 90)
			(layer "B.Fab")
			(effects
				(font
					(size 1.27 1.27)
				)
				(justify mirror)
			)
		)
		(duplicate_pad_numbers_are_jumpers no)
		(fp_poly
			(pts
				(xy 0.2794 -0.1016) (xy -0.2794 -0.1016) (xy -0.2794 0.9906) (xy 0.2794 0.9906)
			)
			(stroke
				(width 0)
				(type default)
			)
			(fill no)
			(layer "B.CrtYd")
		)
		(fp_line
			(start 0.2794 -0.1016)
			(end 0.2794 0.9906)
			(stroke
				(width 0.1)
				(type default)
			)
			(layer "B.Fab")
		)
		(fp_line
			(start -0.2794 -0.1016)
			(end 0.2794 -0.1016)
			(stroke
				(width 0.1)
				(type default)
			)
			(layer "B.Fab")
		)
		(fp_line
			(start 0.2794 0.9906)
			(end -0.2794 0.9906)
			(stroke
				(width 0.1)
				(type default)
			)
			(layer "B.Fab")
		)
		(fp_line
			(start -0.2794 0.9906)
			(end -0.2794 -0.1016)
			(stroke
				(width 0.1)
				(type default)
			)
			(layer "B.Fab")
		)
		(pad "1" smd rect
			(at 0 0 270)
			(size 0.508 0.508)
			(layers "B.Cu" "B.Mask" "B.Paste")
			(net "VR_PVCCIN_CPU1_PH2_VCIN")
		)
		(pad "2" smd rect
			(at 0 0.889 270)
			(size 0.508 0.508)
			(layers "B.Cu" "B.Mask" "B.Paste")
			(net "P5V_STBY")
		)
		(zone
			(layer "B.Cu")
			(hatch none 0.5)
			(connect_pads
				(clearance 0)
			)
			(min_thickness 0.25)
			(keepout
				(tracks allowed)
				(vias not_allowed)
				(pads allowed)
				(copperpour not_allowed)
				(footprints allowed)
			)
			(placement
				(enabled no)
				(sheetname "")
			)
			(fill
				(thermal_gap 0.5)
				(thermal_bridge_width 0.5)
				(island_removal_mode 0)
			)
			(polygon
				(pts
					(xy 32.512 -62.8904) (xy 32.512 -62.3824) (xy 32.893 -62.3824) (xy 32.893 -62.8904)
				)
			)
		)
		(zone
			(layer "B.Cu")
			(hatch none 0.5)
			(connect_pads
				(clearance 0)
			)
			(min_thickness 0.25)
			(keepout
				(tracks not_allowed)
				(vias allowed)
				(pads allowed)
				(copperpour not_allowed)
				(footprints allowed)
			)
			(placement
				(enabled no)
				(sheetname "")
			)
			(fill
				(thermal_gap 0.5)
				(thermal_bridge_width 0.5)
				(island_removal_mode 0)
			)
			(polygon
				(pts
					(xy 32.893 -62.8904) (xy 32.893 -62.3824) (xy 32.512 -62.3824) (xy 32.512 -62.8904)
				)
			)
		)
	)
	(footprint ""
		(layer "B.Cu")
		(at 264.428224 -69.098414 -90)
		(property "Reference" "C5P38"
			(at 0 0 90)
			(layer "B.SilkS")
			(hide yes)
			(effects
				(font
					(size 1.27 1.27)
				)
				(justify mirror)
			)
		)
		(property "Value" ""
			(at 0 0 90)
			(layer "B.Fab")
			(effects
				(font
					(size 1.27 1.27)
				)
				(justify mirror)
			)
		)
		(duplicate_pad_numbers_are_jumpers no)
		(fp_poly
			(pts
				(xy 0.7239 -0.2159) (xy -0.7239 -0.2159) (xy -0.7239 1.9939) (xy 0.7239 1.9939)
			)
			(stroke
				(width 0)
				(type default)
			)
			(fill no)
			(layer "B.CrtYd")
		)
		(fp_line
			(start -0.7239 1.9939)
			(end -0.7239 -0.2159)
			(stroke
				(width 0.1)
				(type default)
			)
			(layer "B.Fab")
		)
		(fp_line
			(start 0.7239 1.9939)
			(end -0.7239 1.9939)
			(stroke
				(width 0.1)
				(type default)
			)
			(layer "B.Fab")
		)
		(fp_line
			(start -0.7239 -0.2159)
			(end 0.7239 -0.2159)
			(stroke
				(width 0.1)
				(type default)
			)
			(layer "B.Fab")
		)
		(fp_line
			(start 0.7239 -0.2159)
			(end 0.7239 1.9939)
			(stroke
				(width 0.1)
				(type default)
			)
			(layer "B.Fab")
		)
		(pad "1" smd rect
			(at 0 0 90)
			(size 1.27 1.016)
			(layers "B.Cu" "B.Mask" "B.Paste")
			(net "PVDDQ_ABC")
		)
		(pad "2" smd rect
			(at 0 1.778 90)
			(size 1.27 1.016)
			(layers "B.Cu" "B.Mask" "B.Paste")
			(net "GND")
		)
		(zone
			(layer "B.Cu")
			(hatch none 0.5)
			(connect_pads
				(clearance 0)
			)
			(min_thickness 0.25)
			(keepout
				(tracks not_allowed)
				(vias allowed)
				(pads allowed)
				(copperpour not_allowed)
				(footprints allowed)
			)
			(placement
				(enabled no)
				(sheetname "")
			)
			(fill
				(thermal_gap 0.5)
				(thermal_bridge_width 0.5)
				(island_removal_mode 0)
			)
			(polygon
				(pts
					(xy 263.920224 -68.463414) (xy 263.920224 -69.733414) (xy 263.158224 -69.733414) (xy 263.158224 -68.463414)
				)
			)
		)
	)
	(footprint ""
		(layer "B.Cu")
		(at 422.70172 -149.098 90)
		(property "Reference" "C2L19"
			(at 0 0 90)
			(layer "B.SilkS")
			(hide yes)
			(effects
				(font
					(size 1.27 1.27)
				)
				(justify mirror)
			)
		)
		(property "Value" ""
			(at 0 0 90)
			(layer "B.Fab")
			(effects
				(font
					(size 1.27 1.27)
				)
				(justify mirror)
			)
		)
		(duplicate_pad_numbers_are_jumpers no)
		(fp_poly
			(pts
				(xy -0.3048 -0.1016) (xy -0.3048 0.9906) (xy 0.3048 0.9906) (xy 0.3048 -0.1016)
			)
			(stroke
				(width 0)
				(type default)
			)
			(fill no)
			(layer "B.CrtYd")
		)
		(fp_line
			(start 0.3048 -0.1016)
			(end 0.3048 0.9906)
			(stroke
				(width 0.1)
				(type default)
			)
			(layer "B.Fab")
		)
		(fp_line
			(start -0.3048 -0.1016)
			(end 0.3048 -0.1016)
			(stroke
				(width 0.1)
				(type default)
			)
			(layer "B.Fab")
		)
		(fp_line
			(start 0.3048 0.9906)
			(end -0.3048 0.9906)
			(stroke
				(width 0.1)
				(type default)
			)
			(layer "B.Fab")
		)
		(fp_line
			(start -0.3048 0.9906)
			(end -0.3048 -0.1016)
			(stroke
				(width 0.1)
				(type default)
			)
			(layer "B.Fab")
		)
		(pad "1" smd rect
			(at 0 0 270)
			(size 0.508 0.508)
			(layers "B.Cu" "B.Mask" "B.Paste")
			(net "SATA6G_PCH_PCIE_UP_SATA_RXP<0>")
		)
		(pad "2" smd rect
			(at 0 0.889 270)
			(size 0.508 0.508)
			(layers "B.Cu" "B.Mask" "B.Paste")
			(net "SATA6G_P0_RX_C_DP")
		)
		(zone
			(layer "B.Cu")
			(hatch none 0.5)
			(connect_pads
				(clearance 0)
			)
			(min_thickness 0.25)
			(keepout
				(tracks allowed)
				(vias not_allowed)
				(pads allowed)
				(copperpour not_allowed)
				(footprints allowed)
			)
			(placement
				(enabled no)
				(sheetname "")
			)
			(fill
				(thermal_gap 0.5)
				(thermal_bridge_width 0.5)
				(island_removal_mode 0)
			)
			(polygon
				(pts
					(xy 422.95572 -149.352) (xy 422.95572 -148.844) (xy 423.33672 -148.844) (xy 423.33672 -149.352)
				)
			)
		)
		(zone
			(layer "B.Cu")
			(hatch none 0.5)
			(connect_pads
				(clearance 0)
			)
			(min_thickness 0.25)
			(keepout
				(tracks not_allowed)
				(vias allowed)
				(pads allowed)
				(copperpour not_allowed)
				(footprints allowed)
			)
			(placement
				(enabled no)
				(sheetname "")
			)
			(fill
				(thermal_gap 0.5)
				(thermal_bridge_width 0.5)
				(island_removal_mode 0)
			)
			(polygon
				(pts
					(xy 423.33672 -149.352) (xy 423.33672 -148.844) (xy 422.95572 -148.844) (xy 422.95572 -149.352)
				)
			)
		)
	)
	(footprint ""
		(layer "B.Cu")
		(at 393.446 -28.575 -90)
		(property "Reference" "C2T35"
			(at 0 0 90)
			(layer "B.SilkS")
			(hide yes)
			(effects
				(font
					(size 1.27 1.27)
				)
				(justify mirror)
			)
		)
		(property "Value" ""
			(at 0 0 90)
			(layer "B.Fab")
			(effects
				(font
					(size 1.27 1.27)
				)
				(justify mirror)
			)
		)
		(duplicate_pad_numbers_are_jumpers no)
		(fp_poly
			(pts
				(xy -0.3048 -0.1016) (xy -0.3048 0.9906) (xy 0.3048 0.9906) (xy 0.3048 -0.1016)
			)
			(stroke
				(width 0)
				(type default)
			)
			(fill no)
			(layer "B.CrtYd")
		)
		(fp_line
			(start -0.3048 0.9906)
			(end -0.3048 -0.1016)
			(stroke
				(width 0.1)
				(type default)
			)
			(layer "B.Fab")
		)
		(fp_line
			(start 0.3048 0.9906)
			(end -0.3048 0.9906)
			(stroke
				(width 0.1)
				(type default)
			)
			(layer "B.Fab")
		)
		(fp_line
			(start -0.3048 -0.1016)
			(end 0.3048 -0.1016)
			(stroke
				(width 0.1)
				(type default)
			)
			(layer "B.Fab")
		)
		(fp_line
			(start 0.3048 -0.1016)
			(end 0.3048 0.9906)
			(stroke
				(width 0.1)
				(type default)
			)
			(layer "B.Fab")
		)
		(pad "1" smd rect
			(at 0 0 90)
			(size 0.508 0.508)
			(layers "B.Cu" "B.Mask" "B.Paste")
			(net "P3V3_STBY")
		)
		(pad "2" smd rect
			(at 0 0.889 90)
			(size 0.508 0.508)
			(layers "B.Cu" "B.Mask" "B.Paste")
			(net "GND")
		)
	)
	(footprint ""
		(layer "B.Cu")
		(at 8.653272 -121.94413 90)
		(property "Reference" "C9M6"
			(at 0 0 90)
			(layer "B.SilkS")
			(hide yes)
			(effects
				(font
					(size 1.27 1.27)
				)
				(justify mirror)
			)
		)
		(property "Value" ""
			(at 0 0 90)
			(layer "B.Fab")
			(effects
				(font
					(size 1.27 1.27)
				)
				(justify mirror)
			)
		)
		(duplicate_pad_numbers_are_jumpers no)
		(fp_rect
			(start 0.3048 0.9906)
			(end -0.3048 -0.1016)
			(stroke
				(width 0)
				(type default)
			)
			(fill no)
			(layer "B.CrtYd")
		)
		(fp_line
			(start 0.3048 -0.1016)
			(end 0.3048 0.9906)
			(stroke
				(width 0.1)
				(type default)
			)
			(layer "B.Fab")
		)
		(fp_line
			(start -0.3048 -0.1016)
			(end 0.3048 -0.1016)
			(stroke
				(width 0.1)
				(type default)
			)
			(layer "B.Fab")
		)
		(fp_line
			(start 0.3048 0.9906)
			(end -0.3048 0.9906)
			(stroke
				(width 0.1)
				(type default)
			)
			(layer "B.Fab")
		)
		(fp_line
			(start -0.3048 0.9906)
			(end -0.3048 -0.1016)
			(stroke
				(width 0.1)
				(type default)
			)
			(layer "B.Fab")
		)
		(pad "1" smd rect
			(at 0 0 270)
			(size 0.508 0.508)
			(layers "B.Cu" "B.Mask" "B.Paste")
			(net "P5V_STBY")
		)
		(pad "2" smd rect
			(at 0 0.889 270)
			(size 0.508 0.508)
			(layers "B.Cu" "B.Mask" "B.Paste")
			(net "GND")
		)
		(zone
			(layer "B.Cu")
			(hatch none 0.5)
			(connect_pads
				(clearance 0)
			)
			(min_thickness 0.25)
			(keepout
				(tracks allowed)
				(vias not_allowed)
				(pads allowed)
				(copperpour not_allowed)
				(footprints allowed)
			)
			(placement
				(enabled no)
				(sheetname "")
			)
			(fill
				(thermal_gap 0.5)
				(thermal_bridge_width 0.5)
				(island_removal_mode 0)
			)
			(polygon
				(pts
					(xy 9.288272 -122.19813) (xy 8.907272 -122.19813) (xy 8.907272 -121.69013) (xy 9.288272 -121.69013)
				)
			)
		)
		(zone
			(layer "B.Cu")
			(hatch none 0.5)
			(connect_pads
				(clearance 0)
			)
			(min_thickness 0.25)
			(keepout
				(tracks not_allowed)
				(vias allowed)
				(pads allowed)
				(copperpour not_allowed)
				(footprints allowed)
			)
			(placement
				(enabled no)
				(sheetname "")
			)
			(fill
				(thermal_gap 0.5)
				(thermal_bridge_width 0.5)
				(island_removal_mode 0)
			)
			(polygon
				(pts
					(xy 9.288272 -122.19813) (xy 8.907272 -122.19813) (xy 8.907272 -121.69013) (xy 9.288272 -121.69013)
				)
			)
		)
	)
	(footprint ""
		(layer "B.Cu")
		(at 444.6778 -64.7446 180)
		(property "Reference" "C2P14"
			(at 0 0 0)
			(layer "B.SilkS")
			(hide yes)
			(effects
				(font
					(size 1.27 1.27)
				)
				(justify mirror)
			)
		)
		(property "Value" ""
			(at 0 0 0)
			(layer "B.Fab")
			(effects
				(font
					(size 1.27 1.27)
				)
				(justify mirror)
			)
		)
		(duplicate_pad_numbers_are_jumpers no)
		(fp_poly
			(pts
				(xy -0.3048 -0.1016) (xy -0.3048 0.9906) (xy 0.3048 0.9906) (xy 0.3048 -0.1016)
			)
			(stroke
				(width 0)
				(type default)
			)
			(fill no)
			(layer "B.CrtYd")
		)
		(fp_line
			(start 0.3048 0.9906)
			(end -0.3048 0.9906)
			(stroke
				(width 0.1)
				(type default)
			)
			(layer "B.Fab")
		)
		(fp_line
			(start 0.3048 -0.1016)
			(end 0.3048 0.9906)
			(stroke
				(width 0.1)
				(type default)
			)
			(layer "B.Fab")
		)
		(fp_line
			(start -0.3048 0.9906)
			(end -0.3048 -0.1016)
			(stroke
				(width 0.1)
				(type default)
			)
			(layer "B.Fab")
		)
		(fp_line
			(start -0.3048 -0.1016)
			(end 0.3048 -0.1016)
			(stroke
				(width 0.1)
				(type default)
			)
			(layer "B.Fab")
		)
		(pad "1" smd rect
			(at 0 0)
			(size 0.508 0.508)
			(layers "B.Cu" "B.Mask" "B.Paste")
			(net "P12V_STBY")
		)
		(pad "2" smd rect
			(at 0 0.889)
			(size 0.508 0.508)
			(layers "B.Cu" "B.Mask" "B.Paste")
			(net "GND")
		)
		(zone
			(layer "B.Cu")
			(hatch none 0.5)
			(connect_pads
				(clearance 0)
			)
			(min_thickness 0.25)
			(keepout
				(tracks not_allowed)
				(vias allowed)
				(pads allowed)
				(copperpour not_allowed)
				(footprints allowed)
			)
			(placement
				(enabled no)
				(sheetname "")
			)
			(fill
				(thermal_gap 0.5)
				(thermal_bridge_width 0.5)
				(island_removal_mode 0)
			)
			(polygon
				(pts
					(xy 444.4238 -65.3796) (xy 444.9318 -65.3796) (xy 444.9318 -64.9986) (xy 444.4238 -64.9986)
				)
			)
		)
		(zone
			(layer "B.Cu")
			(hatch none 0.5)
			(connect_pads
				(clearance 0)
			)
			(min_thickness 0.25)
			(keepout
				(tracks allowed)
				(vias not_allowed)
				(pads allowed)
				(copperpour not_allowed)
				(footprints allowed)
			)
			(placement
				(enabled no)
				(sheetname "")
			)
			(fill
				(thermal_gap 0.5)
				(thermal_bridge_width 0.5)
				(island_removal_mode 0)
			)
			(polygon
				(pts
					(xy 444.4238 -64.9986) (xy 444.9318 -64.9986) (xy 444.9318 -65.3796) (xy 444.4238 -65.3796)
				)
			)
		)
	)
	(footprint ""
		(layer "B.Cu")
		(at 379.481842 -91.021662 180)
		(property "Reference" "R7C26"
			(at 0.8382 -0.67818 180)
			(unlocked yes)
			(layer "B.SilkS")
			(effects
				(font
					(size 0.4064 0.254)
					(thickness 0.1524)
				)
				(justify left mirror)
			)
		)
		(property "Value" ""
			(at 0 0 0)
			(layer "B.Fab")
			(effects
				(font
					(size 1.27 1.27)
				)
				(justify mirror)
			)
		)
		(duplicate_pad_numbers_are_jumpers no)
		(fp_poly
			(pts
				(xy 0.2794 -0.1016) (xy -0.2794 -0.1016) (xy -0.2794 0.9906) (xy 0.2794 0.9906)
			)
			(stroke
				(width 0)
				(type default)
			)
			(fill no)
			(layer "B.CrtYd")
		)
		(fp_line
			(start 0.2794 0.9906)
			(end -0.2794 0.9906)
			(stroke
				(width 0.1)
				(type default)
			)
			(layer "B.Fab")
		)
		(fp_line
			(start 0.2794 -0.1016)
			(end 0.2794 0.9906)
			(stroke
				(width 0.1)
				(type default)
			)
			(layer "B.Fab")
		)
		(fp_line
			(start -0.2794 0.9906)
			(end -0.2794 -0.1016)
			(stroke
				(width 0.1)
				(type default)
			)
			(layer "B.Fab")
		)
		(fp_line
			(start -0.2794 -0.1016)
			(end 0.2794 -0.1016)
			(stroke
				(width 0.1)
				(type default)
			)
			(layer "B.Fab")
		)
		(pad "1" smd rect
			(at 0 0)
			(size 0.508 0.508)
			(layers "B.Cu" "B.Mask" "B.Paste")
			(net "CLK_24M_BMC_LPC")
		)
		(pad "2" smd rect
			(at 0 0.889)
			(size 0.508 0.508)
			(layers "B.Cu" "B.Mask" "B.Paste")
			(net "CLK_24M_BMC_LPC_R")
		)
		(zone
			(layer "B.Cu")
			(hatch none 0.5)
			(connect_pads
				(clearance 0)
			)
			(min_thickness 0.25)
			(keepout
				(tracks not_allowed)
				(vias allowed)
				(pads allowed)
				(copperpour not_allowed)
				(footprints allowed)
			)
			(placement
				(enabled no)
				(sheetname "")
			)
			(fill
				(thermal_gap 0.5)
				(thermal_bridge_width 0.5)
				(island_removal_mode 0)
			)
			(polygon
				(pts
					(xy 379.227842 -91.656662) (xy 379.735842 -91.656662) (xy 379.735842 -91.275662) (xy 379.227842 -91.275662)
				)
			)
		)
		(zone
			(layer "B.Cu")
			(hatch none 0.5)
			(connect_pads
				(clearance 0)
			)
			(min_thickness 0.25)
			(keepout
				(tracks allowed)
				(vias not_allowed)
				(pads allowed)
				(copperpour not_allowed)
				(footprints allowed)
			)
			(placement
				(enabled no)
				(sheetname "")
			)
			(fill
				(thermal_gap 0.5)
				(thermal_bridge_width 0.5)
				(island_removal_mode 0)
			)
			(polygon
				(pts
					(xy 379.227842 -91.275662) (xy 379.735842 -91.275662) (xy 379.735842 -91.656662) (xy 379.227842 -91.656662)
				)
			)
		)
	)
)
